(kicad_pcb
	(version 20260206)
	(generator "pcbnew")
	(generator_version "10.0")
	(general
		(thickness 1.6)
		(legacy_teardrops no)
	)
	(paper "A4")
	(title_block
		(title "03242023_DA0F0TMBIJ0_F0T_Motherboard_J_brd_V01_OCP.brd")
		(comment 1 "Grand Teton / footprints 4711-4715 of 6105")
	)
	(layers
		(0 "F.Cu" signal "TOP")
		(4 "In1.Cu" signal "GND")
		(6 "In2.Cu" signal "IN1")
		(8 "In3.Cu" signal "GND1")
		(10 "In4.Cu" signal "IN2")
		(12 "In5.Cu" signal "GND2")
		(14 "In6.Cu" signal "IN3")
		(16 "In7.Cu" signal "GND3")
		(18 "In8.Cu" signal "VCC")
		(20 "In9.Cu" signal "VCC1")
		(22 "In10.Cu" signal "GND4")
		(24 "In11.Cu" signal "IN4")
		(26 "In12.Cu" signal "GND5")
		(28 "In13.Cu" signal "IN5")
		(30 "In14.Cu" signal "GND6")
		(32 "In15.Cu" signal "IN6")
		(34 "In16.Cu" signal "GND7")
		(2 "B.Cu" signal "BOTTOM")
		(9 "F.Adhes" user "F.Adhesive")
		(11 "B.Adhes" user "B.Adhesive")
		(13 "F.Paste" user "Package Geometry/Pastemask Top")
		(15 "B.Paste" user "Package Geometry/Pastemask Bottom")
		(5 "F.SilkS" user "Ref Des/Silkscreen Top")
		(7 "B.SilkS" user "Ref Des/Silkscreen Bottom")
		(1 "F.Mask" user "Board Geometry/Soldermask Top")
		(3 "B.Mask" user "Board Geometry/Soldermask Bottom")
		(17 "Dwgs.User" user "User.Drawings")
		(19 "Cmts.User" user "User.Comments")
		(21 "Eco1.User" user "User.Eco1")
		(23 "Eco2.User" user "User.Eco2")
		(25 "Edge.Cuts" user "Board Geometry/Outline")
		(27 "Margin" user)
		(31 "F.CrtYd" user "Package Geometry/Place Bound Top")
		(29 "B.CrtYd" user "Package Geometry/Place Bound Bottom")
		(35 "F.Fab" user "Ref Des/Assembly Top")
		(33 "B.Fab" user "Ref Des/Assembly Bottom")
	)
	(footprint ""
		(layer "B.Cu")
		(at 409.284932 -179.457858 180)
		(property "Reference" "PC1573"
			(at 0 0 0)
			(layer "B.SilkS")
			(hide yes)
			(effects
				(font
					(size 1.27 1.27)
				)
				(justify mirror)
			)
		)
		(property "Value" ""
			(at 0 0 0)
			(layer "B.Fab")
			(effects
				(font
					(size 1.27 1.27)
				)
				(justify mirror)
			)
		)
		(duplicate_pad_numbers_are_jumpers no)
		(fp_line
			(start 4.84378 -2.150618)
			(end 4.842256 2.163064)
			(stroke
				(width 0.1524)
				(type default)
			)
			(layer "B.SilkS")
		)
		(fp_line
			(start 4.84378 -2.150618)
			(end 4.53898 -2.150618)
			(stroke
				(width 0.1524)
				(type default)
			)
			(layer "B.SilkS")
		)
		(fp_line
			(start 4.83108 2.150364)
			(end 4.447794 2.149348)
			(stroke
				(width 0.1524)
				(type default)
			)
			(layer "B.SilkS")
		)
		(fp_line
			(start 4.69138 -2.150618)
			(end 4.692396 2.161032)
			(stroke
				(width 0.1524)
				(type default)
			)
			(layer "B.SilkS")
		)
		(fp_line
			(start 4.53898 2.15011)
			(end 4.53898 -2.15011)
			(stroke
				(width 0.1524)
				(type default)
			)
			(layer "B.SilkS")
		)
		(fp_line
			(start 4.53898 -2.15011)
			(end -4.53898 -2.15011)
			(stroke
				(width 0.1524)
				(type default)
			)
			(layer "B.SilkS")
		)
		(fp_line
			(start 4.53898 -2.150618)
			(end 4.539742 2.152142)
			(stroke
				(width 0.1524)
				(type default)
			)
			(layer "B.SilkS")
		)
		(fp_line
			(start -4.53898 2.15011)
			(end 4.53898 2.15011)
			(stroke
				(width 0.1524)
				(type default)
			)
			(layer "B.SilkS")
		)
		(fp_line
			(start -4.53898 -2.15011)
			(end -4.53898 2.15011)
			(stroke
				(width 0.1524)
				(type default)
			)
			(layer "B.SilkS")
		)
		(fp_line
			(start 3.64998 2.15011)
			(end 3.64998 -2.15011)
			(stroke
				(width 0.1)
				(type default)
			)
			(layer "B.Fab")
		)
		(fp_line
			(start 3.64998 -2.15011)
			(end -3.64998 -2.15011)
			(stroke
				(width 0.1)
				(type default)
			)
			(layer "B.Fab")
		)
		(fp_line
			(start -3.64998 2.15011)
			(end 3.64998 2.15011)
			(stroke
				(width 0.1)
				(type default)
			)
			(layer "B.Fab")
		)
		(fp_line
			(start -3.64998 -2.15011)
			(end -3.64998 2.15011)
			(stroke
				(width 0.1)
				(type default)
			)
			(layer "B.Fab")
		)
		(fp_text user "+"
			(at 6.214872 -0.337058 180)
			(unlocked yes)
			(layer "B.SilkS")
			(effects
				(font
					(size 1.905 1.4224)
					(thickness 0.1524)
				)
				(justify left mirror)
			)
		)
		(fp_text user "-"
			(at -5.123688 0.89154 180)
			(unlocked yes)
			(layer "B.SilkS")
			(effects
				(font
					(size 1.905 1.4224)
					(thickness 0.1524)
				)
				(justify left mirror)
			)
		)
		(fp_text user "+"
			(at 6.214872 -0.337058 180)
			(unlocked yes)
			(layer "B.Fab")
			(effects
				(font
					(size 1.905 1.4224)
					(thickness 0.1524)
				)
				(justify left mirror)
			)
		)
		(fp_text user "-"
			(at -4.313174 -0.094488 180)
			(unlocked yes)
			(layer "B.Fab")
			(effects
				(font
					(size 1.905 1.4224)
					(thickness 0.1524)
				)
				(justify left mirror)
			)
		)
		(pad "1" smd rect
			(at 3.199892 0)
			(size 2.413 2.8194)
			(layers "B.Cu" "B.Mask" "B.Paste")
			(net "PVCCINFAON_CPU0")
		)
		(pad "2" smd rect
			(at -3.199892 0)
			(size 2.413 2.8194)
			(layers "B.Cu" "B.Mask" "B.Paste")
			(net "GND")
		)
	)
	(footprint ""
		(layer "B.Cu")
		(at 366.450372 -337.899248)
		(property "Reference" "PR148"
			(at 0 0 0)
			(layer "B.SilkS")
			(hide yes)
			(effects
				(font
					(size 1.27 1.27)
				)
				(justify mirror)
			)
		)
		(property "Value" ""
			(at 0 0 0)
			(layer "B.Fab")
			(effects
				(font
					(size 1.27 1.27)
				)
				(justify mirror)
			)
		)
		(duplicate_pad_numbers_are_jumpers no)
		(fp_line
			(start -0.7874 -0.4064)
			(end -0.7874 0.4064)
			(stroke
				(width 0.1524)
				(type default)
			)
			(layer "B.SilkS")
		)
		(fp_line
			(start -0.7874 0.4064)
			(end 0.7874 0.4064)
			(stroke
				(width 0.1524)
				(type default)
			)
			(layer "B.SilkS")
		)
		(fp_line
			(start 0.7874 -0.4064)
			(end -0.7874 -0.4064)
			(stroke
				(width 0.1524)
				(type default)
			)
			(layer "B.SilkS")
		)
		(fp_line
			(start 0.7874 0.4064)
			(end 0.7874 -0.4064)
			(stroke
				(width 0.1524)
				(type default)
			)
			(layer "B.SilkS")
		)
		(fp_line
			(start -0.67945 -0.3048)
			(end -0.67945 0.3048)
			(stroke
				(width 0.1)
				(type default)
			)
			(layer "B.Fab")
		)
		(fp_line
			(start -0.67945 0.3048)
			(end -0.120396 0.3048)
			(stroke
				(width 0.1)
				(type default)
			)
			(layer "B.Fab")
		)
		(fp_line
			(start -0.12065 -0.3048)
			(end -0.67945 -0.3048)
			(stroke
				(width 0.1)
				(type default)
			)
			(layer "B.Fab")
		)
		(fp_line
			(start -0.12065 -0.2794)
			(end -0.12065 -0.3048)
			(stroke
				(width 0.1)
				(type default)
			)
			(layer "B.Fab")
		)
		(fp_line
			(start -0.120396 0.2794)
			(end 0.12065 0.2794)
			(stroke
				(width 0.1)
				(type default)
			)
			(layer "B.Fab")
		)
		(fp_line
			(start -0.120396 0.3048)
			(end -0.120396 0.2794)
			(stroke
				(width 0.1)
				(type default)
			)
			(layer "B.Fab")
		)
		(fp_line
			(start 0.12065 -0.305054)
			(end 0.12065 -0.2794)
			(stroke
				(width 0.1)
				(type default)
			)
			(layer "B.Fab")
		)
		(fp_line
			(start 0.12065 -0.2794)
			(end -0.12065 -0.2794)
			(stroke
				(width 0.1)
				(type default)
			)
			(layer "B.Fab")
		)
		(fp_line
			(start 0.12065 0.2794)
			(end 0.12065 0.3048)
			(stroke
				(width 0.1)
				(type default)
			)
			(layer "B.Fab")
		)
		(fp_line
			(start 0.12065 0.3048)
			(end 0.67945 0.3048)
			(stroke
				(width 0.1)
				(type default)
			)
			(layer "B.Fab")
		)
		(fp_line
			(start 0.67945 -0.305054)
			(end 0.12065 -0.305054)
			(stroke
				(width 0.1)
				(type default)
			)
			(layer "B.Fab")
		)
		(fp_line
			(start 0.67945 0.3048)
			(end 0.67945 -0.305054)
			(stroke
				(width 0.1)
				(type default)
			)
			(layer "B.Fab")
		)
		(pad "1" smd circle
			(at 0.40005 0 180)
			(size 0 0)
			(layers "B.Cu" "B.Mask" "B.Paste")
			(net "PVCCIN_CPU0_VOS4")
		)
		(pad "2" smd circle
			(at -0.40005 0 180)
			(size 0 0)
			(layers "B.Cu" "B.Mask" "B.Paste")
			(net "PVCCIN_CPU0")
		)
	)
	(footprint ""
		(layer "B.Cu")
		(at 127.83058 -31.529528 90)
		(property "Reference" "R4284"
			(at 0 0 90)
			(layer "B.SilkS")
			(hide yes)
			(effects
				(font
					(size 1.27 1.27)
				)
				(justify mirror)
			)
		)
		(property "Value" ""
			(at 0 0 90)
			(layer "B.Fab")
			(effects
				(font
					(size 1.27 1.27)
				)
				(justify mirror)
			)
		)
		(duplicate_pad_numbers_are_jumpers no)
		(fp_line
			(start 0.7874 -0.4064)
			(end -0.7874 -0.4064)
			(stroke
				(width 0.1524)
				(type default)
			)
			(layer "B.SilkS")
		)
		(fp_line
			(start -0.7874 -0.4064)
			(end -0.7874 0.4064)
			(stroke
				(width 0.1524)
				(type default)
			)
			(layer "B.SilkS")
		)
		(fp_line
			(start 0.7874 0.4064)
			(end 0.7874 -0.4064)
			(stroke
				(width 0.1524)
				(type default)
			)
			(layer "B.SilkS")
		)
		(fp_line
			(start -0.7874 0.4064)
			(end 0.7874 0.4064)
			(stroke
				(width 0.1524)
				(type default)
			)
			(layer "B.SilkS")
		)
		(fp_line
			(start 0.67945 -0.305054)
			(end 0.12065 -0.305054)
			(stroke
				(width 0.1)
				(type default)
			)
			(layer "B.Fab")
		)
		(fp_line
			(start 0.12065 -0.305054)
			(end 0.12065 -0.2794)
			(stroke
				(width 0.1)
				(type default)
			)
			(layer "B.Fab")
		)
		(fp_line
			(start -0.12065 -0.3048)
			(end -0.67945 -0.3048)
			(stroke
				(width 0.1)
				(type default)
			)
			(layer "B.Fab")
		)
		(fp_line
			(start -0.67945 -0.3048)
			(end -0.67945 0.3048)
			(stroke
				(width 0.1)
				(type default)
			)
			(layer "B.Fab")
		)
		(fp_line
			(start 0.12065 -0.2794)
			(end -0.12065 -0.2794)
			(stroke
				(width 0.1)
				(type default)
			)
			(layer "B.Fab")
		)
		(fp_line
			(start -0.12065 -0.2794)
			(end -0.12065 -0.3048)
			(stroke
				(width 0.1)
				(type default)
			)
			(layer "B.Fab")
		)
		(fp_line
			(start 0.12065 0.2794)
			(end 0.12065 0.3048)
			(stroke
				(width 0.1)
				(type default)
			)
			(layer "B.Fab")
		)
		(fp_line
			(start -0.120396 0.2794)
			(end 0.12065 0.2794)
			(stroke
				(width 0.1)
				(type default)
			)
			(layer "B.Fab")
		)
		(fp_line
			(start 0.67945 0.3048)
			(end 0.67945 -0.305054)
			(stroke
				(width 0.1)
				(type default)
			)
			(layer "B.Fab")
		)
		(fp_line
			(start 0.12065 0.3048)
			(end 0.67945 0.3048)
			(stroke
				(width 0.1)
				(type default)
			)
			(layer "B.Fab")
		)
		(fp_line
			(start -0.120396 0.3048)
			(end -0.120396 0.2794)
			(stroke
				(width 0.1)
				(type default)
			)
			(layer "B.Fab")
		)
		(fp_line
			(start -0.67945 0.3048)
			(end -0.120396 0.3048)
			(stroke
				(width 0.1)
				(type default)
			)
			(layer "B.Fab")
		)
		(pad "1" smd circle
			(at 0.40005 0 270)
			(size 0 0)
			(layers "B.Cu" "B.Mask" "B.Paste")
			(net "P3V3_AUX")
		)
		(pad "2" smd circle
			(at -0.40005 0 270)
			(size 0 0)
			(layers "B.Cu" "B.Mask" "B.Paste")
			(net "FM_USB3_1_SWB")
		)
	)
	(footprint ""
		(layer "B.Cu")
		(at 102.495604 -296.05478 180)
		(property "Reference" "C342"
			(at 0 0 0)
			(layer "B.SilkS")
			(hide yes)
			(effects
				(font
					(size 1.27 1.27)
				)
				(justify mirror)
			)
		)
		(property "Value" ""
			(at 0 0 0)
			(layer "B.Fab")
			(effects
				(font
					(size 1.27 1.27)
				)
				(justify mirror)
			)
		)
		(duplicate_pad_numbers_are_jumpers no)
		(fp_line
			(start 1.524 0.762)
			(end 1.524 -0.762)
			(stroke
				(width 0.1524)
				(type default)
			)
			(layer "B.SilkS")
		)
		(fp_line
			(start 1.524 -0.762)
			(end -1.524 -0.762)
			(stroke
				(width 0.1524)
				(type default)
			)
			(layer "B.SilkS")
		)
		(fp_line
			(start -1.524 0.762)
			(end 1.524 0.762)
			(stroke
				(width 0.1524)
				(type default)
			)
			(layer "B.SilkS")
		)
		(fp_line
			(start -1.524 -0.762)
			(end -1.524 0.762)
			(stroke
				(width 0.1524)
				(type default)
			)
			(layer "B.SilkS")
		)
		(fp_line
			(start 1.1049 0.724916)
			(end -1.1049 0.724916)
			(stroke
				(width 0.1)
				(type default)
			)
			(layer "B.Fab")
		)
		(fp_line
			(start 1.1049 -0.724916)
			(end 1.1049 0.724916)
			(stroke
				(width 0.1)
				(type default)
			)
			(layer "B.Fab")
		)
		(fp_line
			(start -1.1049 0.724916)
			(end -1.1049 -0.724916)
			(stroke
				(width 0.1)
				(type default)
			)
			(layer "B.Fab")
		)
		(fp_line
			(start -1.1049 -0.724916)
			(end 1.1049 -0.724916)
			(stroke
				(width 0.1)
				(type default)
			)
			(layer "B.Fab")
		)
		(pad "1" smd rect
			(at 0.889 0 180)
			(size 1.016 1.27)
			(layers "B.Cu" "B.Mask" "B.Paste")
			(net "PVCCIN_CPU1")
		)
		(pad "2" smd rect
			(at -0.889 0 180)
			(size 1.016 1.27)
			(layers "B.Cu" "B.Mask" "B.Paste")
			(net "GND")
		)
	)
	(footprint ""
		(layer "B.Cu")
		(at 236.76991 -130.072892)
		(property "Reference" "R4510"
			(at 0 0 0)
			(layer "B.SilkS")
			(hide yes)
			(effects
				(font
					(size 1.27 1.27)
				)
				(justify mirror)
			)
		)
		(property "Value" ""
			(at 0 0 0)
			(layer "B.Fab")
			(effects
				(font
					(size 1.27 1.27)
				)
				(justify mirror)
			)
		)
		(duplicate_pad_numbers_are_jumpers no)
		(fp_line
			(start -0.7874 -0.4064)
			(end -0.7874 0.4064)
			(stroke
				(width 0.1524)
				(type default)
			)
			(layer "B.SilkS")
		)
		(fp_line
			(start -0.7874 0.4064)
			(end 0.7874 0.4064)
			(stroke
				(width 0.1524)
				(type default)
			)
			(layer "B.SilkS")
		)
		(fp_line
			(start 0.7874 -0.4064)
			(end -0.7874 -0.4064)
			(stroke
				(width 0.1524)
				(type default)
			)
			(layer "B.SilkS")
		)
		(fp_line
			(start 0.7874 0.4064)
			(end 0.7874 -0.4064)
			(stroke
				(width 0.1524)
				(type default)
			)
			(layer "B.SilkS")
		)
		(fp_line
			(start -0.67945 -0.3048)
			(end -0.67945 0.3048)
			(stroke
				(width 0.1)
				(type default)
			)
			(layer "B.Fab")
		)
		(fp_line
			(start -0.67945 0.3048)
			(end -0.120396 0.3048)
			(stroke
				(width 0.1)
				(type default)
			)
			(layer "B.Fab")
		)
		(fp_line
			(start -0.12065 -0.3048)
			(end -0.67945 -0.3048)
			(stroke
				(width 0.1)
				(type default)
			)
			(layer "B.Fab")
		)
		(fp_line
			(start -0.12065 -0.2794)
			(end -0.12065 -0.3048)
			(stroke
				(width 0.1)
				(type default)
			)
			(layer "B.Fab")
		)
		(fp_line
			(start -0.120396 0.2794)
			(end 0.12065 0.2794)
			(stroke
				(width 0.1)
				(type default)
			)
			(layer "B.Fab")
		)
		(fp_line
			(start -0.120396 0.3048)
			(end -0.120396 0.2794)
			(stroke
				(width 0.1)
				(type default)
			)
			(layer "B.Fab")
		)
		(fp_line
			(start 0.12065 -0.305054)
			(end 0.12065 -0.2794)
			(stroke
				(width 0.1)
				(type default)
			)
			(layer "B.Fab")
		)
		(fp_line
			(start 0.12065 -0.2794)
			(end -0.12065 -0.2794)
			(stroke
				(width 0.1)
				(type default)
			)
			(layer "B.Fab")
		)
		(fp_line
			(start 0.12065 0.2794)
			(end 0.12065 0.3048)
			(stroke
				(width 0.1)
				(type default)
			)
			(layer "B.Fab")
		)
		(fp_line
			(start 0.12065 0.3048)
			(end 0.67945 0.3048)
			(stroke
				(width 0.1)
				(type default)
			)
			(layer "B.Fab")
		)
		(fp_line
			(start 0.67945 -0.305054)
			(end 0.12065 -0.305054)
			(stroke
				(width 0.1)
				(type default)
			)
			(layer "B.Fab")
		)
		(fp_line
			(start 0.67945 0.3048)
			(end 0.67945 -0.305054)
			(stroke
				(width 0.1)
				(type default)
			)
			(layer "B.Fab")
		)
		(pad "1" smd circle
			(at 0.40005 0 180)
			(size 0 0)
			(layers "B.Cu" "B.Mask" "B.Paste")
			(net "SMB_HOST_3V3AUX_SCL")
		)
		(pad "2" smd circle
			(at -0.40005 0 180)
			(size 0 0)
			(layers "B.Cu" "B.Mask" "B.Paste")
			(net "SMB_HOST_3V3AUX_SCL_R4")
		)
	)
)
